(kicad_pcb
	(version 20260206)
	(generator "pcbnew")
	(generator_version "10.0")
	(general
		(thickness 1.6)
		(legacy_teardrops no)
	)
	(paper "A4")
	(title_block
		(title "Bryce Canyon_R.DPB_16317-1_OCP.brd")
		(comment 1 "Bryce Canyon / footprints 1555-1561 of 2099")
	)
	(layers
		(0 "F.Cu" signal "TOP")
		(4 "In1.Cu" signal "L2GND")
		(6 "In2.Cu" signal "L3")
		(8 "In3.Cu" signal "L4VCC")
		(10 "In4.Cu" signal "L5VCC")
		(12 "In5.Cu" signal "L6")
		(14 "In6.Cu" signal "L7GND")
		(2 "B.Cu" signal "BOTTOM")
		(9 "F.Adhes" user "F.Adhesive")
		(11 "B.Adhes" user "B.Adhesive")
		(13 "F.Paste" user "Package Geometry/Pastemask Top")
		(15 "B.Paste" user "Package Geometry/Pastemask Bottom")
		(5 "F.SilkS" user "Ref Des/Silkscreen Top")
		(7 "B.SilkS" user "Ref Des/Silkscreen Bottom")
		(1 "F.Mask" user "Board Geometry/Soldermask Top")
		(3 "B.Mask" user "Board Geometry/Soldermask Bottom")
		(17 "Dwgs.User" user "User.Drawings")
		(19 "Cmts.User" user "User.Comments")
		(21 "Eco1.User" user "User.Eco1")
		(23 "Eco2.User" user "User.Eco2")
		(25 "Edge.Cuts" user "Board Geometry/Outline")
		(27 "Margin" user)
		(31 "F.CrtYd" user "Package Geometry/Place Bound Top")
		(29 "B.CrtYd" user "Package Geometry/Place Bound Bottom")
		(35 "F.Fab" user "Ref Des/Assembly Top")
		(33 "B.Fab" user "Ref Des/Assembly Bottom")
	)
	(footprint ""
		(layer "F.Cu")
		(at 143.002 -253.111 90)
		(property "Reference" "R227"
			(at 0 0 90)
			(layer "F.SilkS")
			(hide yes)
			(effects
				(font
					(size 1.27 1.27)
				)
			)
		)
		(property "Value" "4K7R2J-2-GP"
			(at 0.064008 -3.993896 90)
			(unlocked yes)
			(layer "F.Fab")
			(hide yes)
			(effects
				(font
					(size 1.016 1.016)
					(thickness 0.1524)
				)
			)
		)
		(property "Device Type" "R402H16"
			(at 0.064008 -5.517896 90)
			(unlocked yes)
			(layer "F.Fab")
			(hide yes)
			(effects
				(font
					(size 1.016 1.016)
					(thickness 0.1524)
				)
			)
		)
		(duplicate_pad_numbers_are_jumpers no)
		(fp_line
			(start 0.508 -0.9398)
			(end -0.508 -0.9398)
			(stroke
				(width 0.1524)
				(type default)
			)
			(layer "F.SilkS")
		)
		(fp_line
			(start -0.508 -0.9398)
			(end -0.508 0.9398)
			(stroke
				(width 0.1524)
				(type default)
			)
			(layer "F.SilkS")
		)
		(fp_rect
			(start -0.508 0.9398)
			(end 0.508 -0.9398)
			(stroke
				(width 0)
				(type default)
			)
			(fill no)
			(layer "F.CrtYd")
		)
		(fp_rect
			(start -0.508 0.9398)
			(end 0.508 -0.9398)
			(stroke
				(width 0)
				(type default)
			)
			(fill no)
			(layer "F.Fab")
		)
		(pad "1" smd custom
			(at 0 -0.4445 90)
			(size 0.1397 0.1397)
			(layers "F.Cu" "F.Mask" "F.Paste")
			(net "P12V_B")
			(options
				(clearance outline)
				(anchor circle)
			)
			(primitives
				(gr_poly
					(pts
						(arc
							(start -0.1778 -0.2794)
							(mid -0.249642 -0.249642)
							(end -0.2794 -0.1778)
						)
						(arc
							(start -0.2794 0.1778)
							(mid -0.249642 0.249642)
							(end -0.1778 0.2794)
						)
						(arc
							(start 0.1778 0.2794)
							(mid 0.249642 0.249642)
							(end 0.2794 0.1778)
						)
						(arc
							(start 0.2794 -0.1778)
							(mid 0.249642 -0.249642)
							(end 0.1778 -0.2794)
						)
					)
					(width 0)
					(fill yes)
				)
			)
		)
		(pad "2" smd custom
			(at 0 0.4445 90)
			(size 0.1397 0.1397)
			(layers "F.Cu" "F.Mask" "F.Paste")
			(net "SW_HDD_P4")
			(options
				(clearance outline)
				(anchor circle)
			)
			(primitives
				(gr_poly
					(pts
						(arc
							(start -0.1778 -0.2794)
							(mid -0.249642 -0.249642)
							(end -0.2794 -0.1778)
						)
						(arc
							(start -0.2794 0.1778)
							(mid -0.249642 0.249642)
							(end -0.1778 0.2794)
						)
						(arc
							(start 0.1778 0.2794)
							(mid 0.249642 0.249642)
							(end 0.2794 0.1778)
						)
						(arc
							(start 0.2794 -0.1778)
							(mid 0.249642 -0.249642)
							(end 0.1778 -0.2794)
						)
					)
					(width 0)
					(fill yes)
				)
			)
		)
	)
	(footprint ""
		(layer "F.Cu")
		(at 145.161 -265.684 90)
		(property "Reference" "R224"
			(at 0 0 90)
			(layer "F.SilkS")
			(hide yes)
			(effects
				(font
					(size 1.27 1.27)
				)
			)
		)
		(property "Value" "2R6F-GP"
			(at -0.0508 -4.8514 90)
			(unlocked yes)
			(layer "F.Fab")
			(hide yes)
			(effects
				(font
					(size 1.016 1.016)
					(thickness 0.1524)
				)
			)
		)
		(property "Device Type" "R1206H26"
			(at 0 -6.3754 90)
			(unlocked yes)
			(layer "F.Fab")
			(hide yes)
			(effects
				(font
					(size 1.016 1.016)
					(thickness 0.1524)
				)
			)
		)
		(duplicate_pad_numbers_are_jumpers no)
		(fp_line
			(start 1.016 -2.2352)
			(end 1.016 2.2352)
			(stroke
				(width 0.1524)
				(type default)
			)
			(layer "F.SilkS")
		)
		(fp_line
			(start -1.016 -2.2352)
			(end 1.016 -2.2352)
			(stroke
				(width 0.1524)
				(type default)
			)
			(layer "F.SilkS")
		)
		(fp_line
			(start 1.016 2.2352)
			(end -1.016 2.2352)
			(stroke
				(width 0.1524)
				(type default)
			)
			(layer "F.SilkS")
		)
		(fp_line
			(start -1.016 2.2352)
			(end -1.016 -2.2352)
			(stroke
				(width 0.1524)
				(type default)
			)
			(layer "F.SilkS")
		)
		(fp_rect
			(start -1.0922 2.3114)
			(end 1.0922 -2.3114)
			(stroke
				(width 0)
				(type default)
			)
			(fill no)
			(layer "F.CrtYd")
		)
		(fp_poly
			(pts
				(xy -1.0922 -2.3114) (xy 1.0922 -2.3114) (xy 1.0922 2.3114) (xy -1.0922 2.3114)
			)
			(stroke
				(width 0)
				(type default)
			)
			(fill no)
			(layer "F.Fab")
		)
		(pad "1" smd rect
			(at 0 -1.397 90)
			(size 1.651 1.27)
			(layers "F.Cu" "F.Mask" "F.Paste")
			(net "P12V_HDD4")
		)
		(pad "2" smd rect
			(at 0 1.397 90)
			(size 1.651 1.27)
			(layers "F.Cu" "F.Mask" "F.Paste")
			(net "12V_PRE_4")
		)
	)
	(footprint ""
		(layer "F.Cu")
		(at 180.6956 -133.4262 -90)
		(property "Reference" "R469"
			(at 0 0 270)
			(layer "F.SilkS")
			(hide yes)
			(effects
				(font
					(size 1.27 1.27)
				)
			)
		)
		(property "Value" "1KR2F-3-GP"
			(at 0.064008 -3.993896 270)
			(unlocked yes)
			(layer "F.Fab")
			(hide yes)
			(effects
				(font
					(size 1.016 1.016)
					(thickness 0.1524)
				)
			)
		)
		(property "Device Type" "R402H16"
			(at 0.064008 -5.517896 270)
			(unlocked yes)
			(layer "F.Fab")
			(hide yes)
			(effects
				(font
					(size 1.016 1.016)
					(thickness 0.1524)
				)
			)
		)
		(duplicate_pad_numbers_are_jumpers no)
		(fp_line
			(start -0.508 -0.9398)
			(end -0.508 0.9398)
			(stroke
				(width 0.1524)
				(type default)
			)
			(layer "F.SilkS")
		)
		(fp_line
			(start 0.508 -0.9398)
			(end -0.508 -0.9398)
			(stroke
				(width 0.1524)
				(type default)
			)
			(layer "F.SilkS")
		)
		(fp_rect
			(start -0.508 0.9398)
			(end 0.508 -0.9398)
			(stroke
				(width 0)
				(type default)
			)
			(fill no)
			(layer "F.CrtYd")
		)
		(fp_rect
			(start -0.508 0.9398)
			(end 0.508 -0.9398)
			(stroke
				(width 0)
				(type default)
			)
			(fill no)
			(layer "F.Fab")
		)
		(pad "1" smd custom
			(at 0 -0.4445 270)
			(size 0.1397 0.1397)
			(layers "F.Cu" "F.Mask" "F.Paste")
			(net "P3V3_STBY_B")
			(options
				(clearance outline)
				(anchor circle)
			)
			(primitives
				(gr_poly
					(pts
						(arc
							(start -0.1778 -0.2794)
							(mid -0.249642 -0.249642)
							(end -0.2794 -0.1778)
						)
						(arc
							(start -0.2794 0.1778)
							(mid -0.249642 0.249642)
							(end -0.1778 0.2794)
						)
						(arc
							(start 0.1778 0.2794)
							(mid 0.249642 0.249642)
							(end 0.2794 0.1778)
						)
						(arc
							(start 0.2794 -0.1778)
							(mid 0.249642 -0.249642)
							(end 0.1778 -0.2794)
						)
					)
					(width 0)
					(fill yes)
				)
			)
		)
		(pad "2" smd custom
			(at 0 0.4445 270)
			(size 0.1397 0.1397)
			(layers "F.Cu" "F.Mask" "F.Paste")
			(net "SW_PWR_R_HDD17")
			(options
				(clearance outline)
				(anchor circle)
			)
			(primitives
				(gr_poly
					(pts
						(arc
							(start -0.1778 -0.2794)
							(mid -0.249642 -0.249642)
							(end -0.2794 -0.1778)
						)
						(arc
							(start -0.2794 0.1778)
							(mid -0.249642 0.249642)
							(end -0.1778 0.2794)
						)
						(arc
							(start 0.1778 0.2794)
							(mid 0.249642 0.249642)
							(end 0.2794 0.1778)
						)
						(arc
							(start 0.2794 -0.1778)
							(mid 0.249642 -0.249642)
							(end 0.1778 -0.2794)
						)
					)
					(width 0)
					(fill yes)
				)
			)
		)
	)
	(footprint ""
		(layer "F.Cu")
		(at 260.051042 -94.953836 180)
		(property "Reference" "C2"
			(at 0 0 180)
			(layer "F.SilkS")
			(hide yes)
			(effects
				(font
					(size 1.27 1.27)
				)
			)
		)
		(property "Value" "SC22U25V6KX-2-GP-U"
			(at -2.860802 -5.279644 180)
			(unlocked yes)
			(layer "F.Fab")
			(hide yes)
			(effects
				(font
					(size 1.016 1.016)
					(thickness 0.1524)
				)
			)
		)
		(property "Device Type" "C1206-TO0D3H75"
			(at -2.860802 -6.803644 180)
			(unlocked yes)
			(layer "F.Fab")
			(hide yes)
			(effects
				(font
					(size 1.016 1.016)
					(thickness 0.1524)
				)
			)
		)
		(duplicate_pad_numbers_are_jumpers no)
		(fp_line
			(start 1.3081 2.3749)
			(end -1.3081 2.3749)
			(stroke
				(width 0.1524)
				(type default)
			)
			(layer "F.SilkS")
		)
		(fp_line
			(start 1.3081 -2.3749)
			(end 1.3081 2.3749)
			(stroke
				(width 0.1524)
				(type default)
			)
			(layer "F.SilkS")
		)
		(fp_line
			(start -1.3081 2.3749)
			(end -1.3081 -2.3749)
			(stroke
				(width 0.1524)
				(type default)
			)
			(layer "F.SilkS")
		)
		(fp_line
			(start -1.3081 -2.3749)
			(end 1.3081 -2.3749)
			(stroke
				(width 0.1524)
				(type default)
			)
			(layer "F.SilkS")
		)
		(fp_rect
			(start -0.8001 1.6002)
			(end 0.8001 -1.6002)
			(stroke
				(width 0)
				(type default)
			)
			(fill no)
			(layer "F.CrtYd")
		)
		(fp_poly
			(pts
				(xy -1.5621 2.4511) (xy -1.5621 1.6002) (xy 0.8001 1.6002) (xy 0.8001 -1.6002) (xy -0.8001 -1.6002)
				(xy -0.8001 1.5875) (xy -1.5621 1.5875) (xy -1.5621 -2.4511) (xy 1.5621 -2.4511) (xy 1.5621 2.4511)
			)
			(stroke
				(width 0)
				(type default)
			)
			(fill no)
			(layer "F.CrtYd")
		)
		(fp_rect
			(start -1.5621 2.4511)
			(end 1.5621 -2.4511)
			(stroke
				(width 0)
				(type default)
			)
			(fill no)
			(layer "F.Fab")
		)
		(pad "1" smd rect
			(at 0 -1.392936 180)
			(size 2.1082 1.4478)
			(layers "F.Cu" "F.Mask" "F.Paste")
			(net "P12V_B")
		)
		(pad "2" smd rect
			(at 0 1.392936 180)
			(size 2.1082 1.4478)
			(layers "F.Cu" "F.Mask" "F.Paste")
			(net "GND")
		)
	)
	(footprint ""
		(layer "F.Cu")
		(at 190.8302 -262.128 90)
		(property "Reference" "C102"
			(at 0 0 90)
			(layer "F.SilkS")
			(hide yes)
			(effects
				(font
					(size 1.27 1.27)
				)
			)
		)
		(property "Value" "SCD01U50V2KX-1GP"
			(at 1.1811 -2.7051 90)
			(unlocked yes)
			(layer "F.Fab")
			(hide yes)
			(effects
				(font
					(size 1.016 1.016)
					(thickness 0.1524)
				)
			)
		)
		(property "Device Type" "C402H22"
			(at 1.1811 -4.2291 90)
			(unlocked yes)
			(layer "F.Fab")
			(hide yes)
			(effects
				(font
					(size 1.016 1.016)
					(thickness 0.1524)
				)
			)
		)
		(duplicate_pad_numbers_are_jumpers no)
		(fp_rect
			(start -0.4318 0.9525)
			(end 0.4318 -0.9525)
			(stroke
				(width 0)
				(type default)
			)
			(fill no)
			(layer "F.CrtYd")
		)
		(fp_rect
			(start -0.4318 0.9525)
			(end 0.4318 -0.9525)
			(stroke
				(width 0)
				(type default)
			)
			(fill no)
			(layer "F.Fab")
		)
		(pad "1" smd custom
			(at 0 -0.4445 90)
			(size 0.1524 0.1524)
			(layers "F.Cu" "F.Mask" "F.Paste")
			(net "HDD_PRSNT_5")
			(options
				(clearance outline)
				(anchor circle)
			)
			(primitives
				(gr_poly
					(pts
						(arc
							(start 0.3048 -0.2032)
							(mid 0.275042 -0.275042)
							(end 0.2032 -0.3048)
						)
						(arc
							(start -0.2032 -0.3048)
							(mid -0.275042 -0.275042)
							(end -0.3048 -0.2032)
						)
						(arc
							(start -0.3048 0.2032)
							(mid -0.275042 0.275042)
							(end -0.2032 0.3048)
						)
						(arc
							(start 0.2032 0.3048)
							(mid 0.275042 0.275042)
							(end 0.3048 0.2032)
						)
					)
					(width 0)
					(fill yes)
				)
			)
		)
		(pad "2" smd custom
			(at 0 0.4445 90)
			(size 0.1524 0.1524)
			(layers "F.Cu" "F.Mask" "F.Paste")
			(net "GND")
			(options
				(clearance outline)
				(anchor circle)
			)
			(primitives
				(gr_poly
					(pts
						(arc
							(start 0.3048 -0.2032)
							(mid 0.275042 -0.275042)
							(end 0.2032 -0.3048)
						)
						(arc
							(start -0.2032 -0.3048)
							(mid -0.275042 -0.275042)
							(end -0.3048 -0.2032)
						)
						(arc
							(start -0.3048 0.2032)
							(mid -0.275042 0.275042)
							(end -0.2032 0.3048)
						)
						(arc
							(start 0.2032 0.3048)
							(mid 0.275042 0.275042)
							(end 0.3048 0.2032)
						)
					)
					(width 0)
					(fill yes)
				)
			)
		)
	)
	(footprint ""
		(layer "F.Cu")
		(at 181.3052 -372.6942 -90)
		(property "Reference" "R990"
			(at 0 0 270)
			(layer "F.SilkS")
			(hide yes)
			(effects
				(font
					(size 1.27 1.27)
				)
			)
		)
		(property "Value" "10KR2J-3-GP"
			(at 0.064008 -3.993896 270)
			(unlocked yes)
			(layer "F.Fab")
			(hide yes)
			(effects
				(font
					(size 1.016 1.016)
					(thickness 0.1524)
				)
			)
		)
		(property "Device Type" "R402H16"
			(at 0.064008 -5.517896 270)
			(unlocked yes)
			(layer "F.Fab")
			(hide yes)
			(effects
				(font
					(size 1.016 1.016)
					(thickness 0.1524)
				)
			)
		)
		(duplicate_pad_numbers_are_jumpers no)
		(fp_line
			(start -0.508 -0.9398)
			(end -0.508 0.9398)
			(stroke
				(width 0.1524)
				(type default)
			)
			(layer "F.SilkS")
		)
		(fp_line
			(start 0.508 -0.9398)
			(end -0.508 -0.9398)
			(stroke
				(width 0.1524)
				(type default)
			)
			(layer "F.SilkS")
		)
		(fp_rect
			(start -0.508 0.9398)
			(end 0.508 -0.9398)
			(stroke
				(width 0)
				(type default)
			)
			(fill no)
			(layer "F.CrtYd")
		)
		(fp_rect
			(start -0.508 0.9398)
			(end 0.508 -0.9398)
			(stroke
				(width 0)
				(type default)
			)
			(fill no)
			(layer "F.Fab")
		)
		(pad "1" smd custom
			(at 0 -0.4445 270)
			(size 0.1397 0.1397)
			(layers "F.Cu" "F.Mask" "F.Paste")
			(net "GND")
			(options
				(clearance outline)
				(anchor circle)
			)
			(primitives
				(gr_poly
					(pts
						(arc
							(start -0.1778 -0.2794)
							(mid -0.249642 -0.249642)
							(end -0.2794 -0.1778)
						)
						(arc
							(start -0.2794 0.1778)
							(mid -0.249642 0.249642)
							(end -0.1778 0.2794)
						)
						(arc
							(start 0.1778 0.2794)
							(mid 0.249642 0.249642)
							(end 0.2794 0.1778)
						)
						(arc
							(start 0.2794 -0.1778)
							(mid 0.249642 -0.249642)
							(end 0.1778 -0.2794)
						)
					)
					(width 0)
					(fill yes)
				)
			)
		)
		(pad "2" smd custom
			(at 0 0.4445 270)
			(size 0.1397 0.1397)
			(layers "F.Cu" "F.Mask" "F.Paste")
			(net "MB0_RETRY_R")
			(options
				(clearance outline)
				(anchor circle)
			)
			(primitives
				(gr_poly
					(pts
						(arc
							(start -0.1778 -0.2794)
							(mid -0.249642 -0.249642)
							(end -0.2794 -0.1778)
						)
						(arc
							(start -0.2794 0.1778)
							(mid -0.249642 0.249642)
							(end -0.1778 0.2794)
						)
						(arc
							(start 0.1778 0.2794)
							(mid 0.249642 0.249642)
							(end 0.2794 0.1778)
						)
						(arc
							(start 0.2794 -0.1778)
							(mid 0.249642 -0.249642)
							(end 0.1778 -0.2794)
						)
					)
					(width 0)
					(fill yes)
				)
			)
		)
	)
	(footprint ""
		(layer "F.Cu")
		(at 237.363 -351.0534)
		(property "Reference" "D46"
			(at 0 0 0)
			(layer "F.SilkS")
			(hide yes)
			(effects
				(font
					(size 1.27 1.27)
				)
			)
		)
		(property "Value" "SMCJ14A-13-F-GP"
			(at -4.445 1.1684 0)
			(unlocked yes)
			(layer "F.Fab")
			(hide yes)
			(effects
				(font
					(size 1.016 1.016)
					(thickness 0.1524)
				)
			)
		)
		(property "Device Type" "D795930AKH104"
			(at -4.445 -0.3556 0)
			(unlocked yes)
			(layer "F.Fab")
			(hide yes)
			(effects
				(font
					(size 1.016 1.016)
					(thickness 0.1524)
				)
			)
		)
		(duplicate_pad_numbers_are_jumpers no)
		(fp_line
			(start -3.2004 -4.8641)
			(end -3.2004 4.8641)
			(stroke
				(width 0.1524)
				(type default)
			)
			(layer "F.SilkS")
		)
		(fp_line
			(start -3.2004 4.8641)
			(end 3.2004 4.8641)
			(stroke
				(width 0.1524)
				(type default)
			)
			(layer "F.SilkS")
		)
		(fp_line
			(start 3.2004 -4.8641)
			(end -3.2004 -4.8641)
			(stroke
				(width 0.1524)
				(type default)
			)
			(layer "F.SilkS")
		)
		(fp_line
			(start 3.2004 4.8641)
			(end 3.2004 -4.8641)
			(stroke
				(width 0.1524)
				(type default)
			)
			(layer "F.SilkS")
		)
		(fp_line
			(start 3.2004 5.0419)
			(end -3.2004 5.0419)
			(stroke
				(width 0.508)
				(type default)
			)
			(layer "F.SilkS")
		)
		(fp_poly
			(pts
				(xy -2.9464 3.429) (xy -1.4859 3.429) (xy -1.4859 3.9751) (xy 1.4859 3.9751) (xy 1.4859 3.429) (xy 2.9464 3.429)
				(xy 2.9464 -3.429) (xy 1.4859 -3.429) (xy 1.4859 -3.9751) (xy -1.4859 -3.9751) (xy -1.4859 -3.429)
				(xy -2.9464 -3.429)
			)
			(stroke
				(width 0)
				(type default)
			)
			(fill no)
			(layer "F.CrtYd")
		)
		(fp_poly
			(pts
				(xy -3.4544 4.9403) (xy -3.4544 -4.9403) (xy 3.4544 -4.9403) (xy 3.4544 -3.429) (xy 1.4859 -3.429)
				(xy 1.4859 -3.9751) (xy -1.4859 -3.9751) (xy -1.4859 -3.429) (xy -2.9464 -3.429) (xy -2.9464 3.429)
				(xy -1.4859 3.429) (xy -1.4859 3.9751) (xy 1.4859 3.9751) (xy 1.4859 3.429) (xy 2.9464 3.429) (xy 2.9464 -3.4163)
				(xy 3.4544 -3.4163) (xy 3.4544 4.9403)
			)
			(stroke
				(width 0)
				(type default)
			)
			(fill no)
			(layer "F.CrtYd")
		)
		(fp_rect
			(start -3.4544 4.9403)
			(end 3.4544 -4.9403)
			(stroke
				(width 0)
				(type default)
			)
			(fill no)
			(layer "F.Fab")
		)
		(pad "A" smd rect
			(at 0 -3.592068)
			(size 3.2258 2.032)
			(layers "F.Cu" "F.Mask" "F.Paste")
			(net "GND")
		)
		(pad "K" smd rect
			(at 0 3.592068)
			(size 3.2258 2.032)
			(layers "F.Cu" "F.Mask" "F.Paste")
			(net "P12V_IN")
		)
	)
)
